# TIMECARD (Time Appliance Project (Time Card)) — schematic netlist excerpt (pin names and nets, part order shuffled) for the footprints in the layout excerpt that follows; sources: Cadence DE-HDL packaged netlist, KiCad conversion of R4006-B0001-02_R01.brd

R383  RESISTOR  4.7KOHM 1%  pkg SMC_0402R_H016  page 23 : \1\ = XP3R3V_FPGA ; \2\ = SMA2_SIG_IN_BF_EN_N
TP35  TP_PIONT  pkg TP010CT020B030_PTH  page 25 : \1\ = SMA4_SIG_OUT_BF_EN_N

(kicad_pcb
	(version 20260206)
	(generator "pcbnew")
	(generator_version "10.0")
	(general
		(thickness 1.6)
		(legacy_teardrops no)
	)
	(paper "A4")
	(title_block
		(title "timecard-production-celestica-r4006 — R4006-B0001-02_R01.brd")
		(comment 1 "Time Appliance Project (Time Card) / footprints 611-612 of 1113")
	)
	(layers
		(0 "F.Cu" signal "TOP")
		(4 "In1.Cu" signal "L02_GND1")
		(6 "In2.Cu" signal "L03_SIG1")
		(8 "In3.Cu" signal "L04_GND2")
		(10 "In4.Cu" signal "L05_VCC1")
		(12 "In5.Cu" signal "L06_VCC2")
		(14 "In6.Cu" signal "L07_GND3")
		(16 "In7.Cu" signal "L08_SIG2")
		(18 "In8.Cu" signal "L09_GND4")
		(2 "B.Cu" signal "BOTTOM")
		(9 "F.Adhes" user "F.Adhesive")
		(11 "B.Adhes" user "B.Adhesive")
		(13 "F.Paste" user "Package Geometry/Pastemask Top")
		(15 "B.Paste" user "Package Geometry/Pastemask Bottom")
		(5 "F.SilkS" user "Ref Des/Silkscreen Top")
		(7 "B.SilkS" user "Ref Des/Silkscreen Bottom")
		(1 "F.Mask" user "Board Geometry/Soldermask Top")
		(3 "B.Mask" user "Board Geometry/Soldermask Bottom")
		(17 "Dwgs.User" user "User.Drawings")
		(19 "Cmts.User" user "User.Comments")
		(21 "Eco1.User" user "User.Eco1")
		(23 "Eco2.User" user "User.Eco2")
		(25 "Edge.Cuts" user "Board Geometry/Outline")
		(27 "Margin" user)
		(31 "F.CrtYd" user "Package Geometry/Place Bound Top")
		(29 "B.CrtYd" user "Package Geometry/Place Bound Bottom")
		(35 "F.Fab" user "Ref Des/Assembly Top")
		(33 "B.Fab" user "Ref Des/Assembly Bottom")
	)
	(footprint ""
		(layer "F.Cu")
		(at 13.589 -41.91)
		(property "Reference" "R383"
			(at 0 1.17475 0)
			(unlocked yes)
			(layer "F.SilkS")
			(effects
				(font
					(size 0.635 0.4064)
					(thickness 0.1524)
				)
			)
		)
		(property "Value" "VAL*"
			(at 0.02032 2.13233 0)
			(unlocked yes)
			(layer "F.Fab")
			(hide yes)
			(effects
				(font
					(size 0.7874 0.5842)
					(thickness 0.1524)
				)
			)
		)
		(property "Tolerance" "TOL*"
			(at 0.044704 3.05435 0)
			(unlocked yes)
			(layer "Cmts.User")
			(hide yes)
			(effects
				(font
					(size 0.7874 0.5842)
					(thickness 0.1524)
				)
			)
		)
		(property "User Part Number" "PARTNUM*"
			(at 0.02032 4.024884 0)
			(unlocked yes)
			(layer "Cmts.User")
			(hide yes)
			(effects
				(font
					(size 0.7874 0.5842)
					(thickness 0.1524)
				)
			)
		)
		(property "Device Type" "RESISTOR-G155-14701-01,4.7KOHMA"
			(at 0.008382 1.210564 0)
			(unlocked yes)
			(layer "F.Fab")
			(hide yes)
			(effects
				(font
					(size 0.7874 0.5842)
					(thickness 0.1524)
				)
			)
		)
		(duplicate_pad_numbers_are_jumpers no)
		(fp_line
			(start -1.143 -0.5588)
			(end -1.143 0.5588)
			(stroke
				(width 0.1)
				(type default)
			)
			(layer "F.SilkS")
		)
		(fp_line
			(start -1.143 0.5588)
			(end 1.143 0.5588)
			(stroke
				(width 0.1)
				(type default)
			)
			(layer "F.SilkS")
		)
		(fp_line
			(start 1.143 -0.5588)
			(end -1.143 -0.5588)
			(stroke
				(width 0.1)
				(type default)
			)
			(layer "F.SilkS")
		)
		(fp_line
			(start 1.143 0.5588)
			(end 1.143 -0.5588)
			(stroke
				(width 0.1)
				(type default)
			)
			(layer "F.SilkS")
		)
		(fp_rect
			(start 1.143 0.5588)
			(end -1.143 -0.5588)
			(stroke
				(width 0)
				(type default)
			)
			(fill no)
			(layer "F.CrtYd")
		)
		(fp_line
			(start -0.508 -0.3048)
			(end -0.508 0.3048)
			(stroke
				(width 0.1)
				(type default)
			)
			(layer "F.Fab")
		)
		(fp_line
			(start -0.508 0.3048)
			(end 0.508 0.3048)
			(stroke
				(width 0.1)
				(type default)
			)
			(layer "F.Fab")
		)
		(fp_line
			(start 0.508 -0.3048)
			(end -0.508 -0.3048)
			(stroke
				(width 0.1)
				(type default)
			)
			(layer "F.Fab")
		)
		(fp_line
			(start 0.508 0.3048)
			(end 0.508 -0.3048)
			(stroke
				(width 0.1)
				(type default)
			)
			(layer "F.Fab")
		)
		(pad "1" smd rect
			(at -0.5334 0)
			(size 0.7112 0.6096)
			(layers "F.Cu" "F.Mask" "F.Paste")
			(net "XP3R3V_FPGA")
		)
		(pad "2" smd rect
			(at 0.5334 0)
			(size 0.7112 0.6096)
			(layers "F.Cu" "F.Mask" "F.Paste")
			(net "SMA2_SIG_IN_BF_EN_N")
		)
		(zone
			(layer "F.Cu")
			(hatch none 0.5)
			(connect_pads
				(clearance 0)
			)
			(min_thickness 0.25)
			(keepout
				(tracks not_allowed)
				(vias allowed)
				(pads allowed)
				(copperpour not_allowed)
				(footprints allowed)
			)
			(placement
				(enabled no)
				(sheetname "")
			)
			(fill
				(thermal_gap 0.5)
				(thermal_bridge_width 0.5)
				(island_removal_mode 0)
			)
			(polygon
				(pts
					(xy 13.6652 -41.6052) (xy 13.6652 -42.2148) (xy 13.5128 -42.2148) (xy 13.5128 -41.6052)
				)
			)
		)
		(zone
			(layer "F.Cu")
			(hatch none 0.5)
			(connect_pads
				(clearance 0)
			)
			(min_thickness 0.25)
			(keepout
				(tracks allowed)
				(vias not_allowed)
				(pads allowed)
				(copperpour not_allowed)
				(footprints allowed)
			)
			(placement
				(enabled no)
				(sheetname "")
			)
			(fill
				(thermal_gap 0.5)
				(thermal_bridge_width 0.5)
				(island_removal_mode 0)
			)
			(polygon
				(pts
					(xy 13.6652 -41.6052) (xy 13.6652 -42.2148) (xy 13.5128 -42.2148) (xy 13.5128 -41.6052)
				)
			)
		)
	)
	(footprint ""
		(layer "F.Cu")
		(at 16.129 -21.463)
		(property "Reference" "TP35"
			(at -0.08763 -0.9398 90)
			(unlocked yes)
			(layer "F.SilkS")
			(effects
				(font
					(size 0.7874 0.5842)
					(thickness 0.1524)
				)
				(justify left)
			)
		)
		(property "Value" ""
			(at 0 0 0)
			(layer "F.Fab")
			(effects
				(font
					(size 1.27 1.27)
				)
			)
		)
		(property "Device Type" "TP_PIONT-TP010CT020B030_PTH-TPA"
			(at -1.341882 0.996696 0)
			(unlocked yes)
			(layer "F.Fab")
			(hide yes)
			(effects
				(font
					(size 0.7874 0.5842)
					(thickness 0.000001)
				)
				(justify left)
			)
		)
		(duplicate_pad_numbers_are_jumpers no)
		(fp_poly
			(pts
				(arc
					(start 0.889 0)
					(mid -0.889 0)
					(end 0.889 0)
				)
			)
			(stroke
				(width 0)
				(type default)
			)
			(fill no)
			(layer "B.CrtYd")
		)
		(fp_poly
			(pts
				(arc
					(start 0.889 0)
					(mid -0.889 0)
					(end 0.889 0)
				)
			)
			(stroke
				(width 0)
				(type default)
			)
			(fill no)
			(layer "F.CrtYd")
		)
		(pad "1" thru_hole circle
			(at 0 0)
			(size 0.508 0.508)
			(drill 0.254)
			(layers "*.Cu" "*.Mask")
			(remove_unused_layers no)
			(net "SMA4_SIG_OUT_BF_EN_N")
			(clearance 0.1016)
			(padstack
				(mode front_inner_back)
				(layer "Inner"
					(shape circle)
					(size 0.508 0.508)
					(clearance 0.1016)
				)
				(layer "B.Cu"
					(shape circle)
					(size 0.762 0.762)
					(clearance -0.0254)
				)
			)
		)
	)
)
